FILE_TYPE = MACRO_DRAWING;
SET COLOR_WIRE YELLOW;
SET COLOR_PROP AQUA;
SET COLOR_DOT WHITE;
SET COLOR_ARC YELLOW;
SET COLOR_BODY SKYBLUE;
SET COLOR_NOTE ORANGE;
SET PROP_DISPLAY VALUE;
FORCEADD SYNONYM..1
(2100 2100);
PAINT GREEN (2100 2100);
FORCEPROP 2 LASTPIN (2150 2100) SIG_NAME A<SIZE-1..0>\NAC\I
J 0
(2200 2110);
PAINT ORANGE (2200 2110);
FORCEPROP 1 LAST NEEDS_NO_SIZE TRUE
J 0
(2125 2175);
PAINT GREEN (2125 2175);
DISPLAY INVISIBLE (2125 2175);
FORCEPROP 2 LAST PATH 1P
J 0
(2100 2200);
PAINT ORANGE (2100 2200);
DISPLAY BOTH (2100 2200);
FORCEPROP 1 LAST BODY_TYPE PLUMBING
J 0
(2100 2150);
PAINT SKYBLUE (2100 2150);
DISPLAY INVISIBLE (2100 2150);
FORCEPROP 2 LASTPIN (2050 2100) SIG_NAME GND\G\R SIZE
J 2
(2000 2110);
PAINT ORANGE (2000 2110);
FORCEADD DRAWING..1
(2350 1750);
PAINT GREEN (2350 1750);
FORCEPROP 1 LAST LAST_MODIFIED Mon Oct  4 09:08:54 1993
J 0
(2150 1500);
PAINT GREEN (2150 1500);
DISPLAY BOTH (2150 1500);
FORCEPROP 0 LAST ABBREV GND
J 0
(2200 1600);
PAINT ORANGE (2200 1600);
DISPLAY BOTH (2200 1600);
FORCEPROP 0 LAST TITLE GND
J 0
(2200 1700);
PAINT ORANGE (2200 1700);
DISPLAY BOTH (2200 1700);
QUIT
